(kicad_pcb
	(version 20260206)
	(generator "pcbnew")
	(generator_version "10.0")
	(general
		(thickness 1.6)
		(legacy_teardrops no)
	)
	(paper "A4")
	(title_block
		(title "Bryce Canyon_IOM_M2_16342-2_OCP.brd")
		(comment 1 "Bryce Canyon / footprints 777-784 of 1146")
	)
	(layers
		(0 "F.Cu" signal "TOP")
		(4 "In1.Cu" signal "L2GND")
		(6 "In2.Cu" signal "L3")
		(8 "In3.Cu" signal "L4VCC")
		(10 "In4.Cu" signal "L5VCC")
		(12 "In5.Cu" signal "L6")
		(14 "In6.Cu" signal "L7GND")
		(2 "B.Cu" signal "BOTTOM")
		(9 "F.Adhes" user "F.Adhesive")
		(11 "B.Adhes" user "B.Adhesive")
		(13 "F.Paste" user "Package Geometry/Pastemask Top")
		(15 "B.Paste" user "Package Geometry/Pastemask Bottom")
		(5 "F.SilkS" user "Ref Des/Silkscreen Top")
		(7 "B.SilkS" user "Ref Des/Silkscreen Bottom")
		(1 "F.Mask" user "Board Geometry/Soldermask Top")
		(3 "B.Mask" user "Board Geometry/Soldermask Bottom")
		(17 "Dwgs.User" user "User.Drawings")
		(19 "Cmts.User" user "User.Comments")
		(21 "Eco1.User" user "User.Eco1")
		(23 "Eco2.User" user "User.Eco2")
		(25 "Edge.Cuts" user "Board Geometry/Outline")
		(27 "Margin" user)
		(31 "F.CrtYd" user "Package Geometry/Place Bound Top")
		(29 "B.CrtYd" user "Package Geometry/Place Bound Bottom")
		(35 "F.Fab" user "Ref Des/Assembly Top")
		(33 "B.Fab" user "Ref Des/Assembly Bottom")
	)
	(footprint ""
		(layer "B.Cu")
		(at 224.989644 -74.10323 90)
		(property "Reference" "C650"
			(at 0 0 90)
			(layer "B.SilkS")
			(hide yes)
			(effects
				(font
					(size 1.27 1.27)
				)
				(justify mirror)
			)
		)
		(property "Value" "SC10U6D3V5KX-4GP"
			(at 0.0762 -6.1214 90)
			(unlocked yes)
			(layer "B.Fab")
			(hide yes)
			(effects
				(font
					(size 1.016 1.016)
					(thickness 0.1524)
				)
				(justify mirror)
			)
		)
		(property "Device Type" "C805H58"
			(at 0.0762 -8.1534 90)
			(unlocked yes)
			(layer "B.Fab")
			(hide yes)
			(effects
				(font
					(size 1.016 1.016)
					(thickness 0.1524)
				)
				(justify mirror)
			)
		)
		(duplicate_pad_numbers_are_jumpers no)
		(fp_line
			(start -0.635 0)
			(end 0.635 0)
			(stroke
				(width 0.508)
				(type default)
			)
			(layer "B.SilkS")
		)
		(fp_rect
			(start 0.9652 1.778)
			(end -0.9652 -1.778)
			(stroke
				(width 0)
				(type default)
			)
			(fill no)
			(layer "B.CrtYd")
		)
		(fp_poly
			(pts
				(xy 0.9652 -1.778) (xy -0.9652 -1.778) (xy -0.9652 1.778) (xy 0.9652 1.778)
			)
			(stroke
				(width 0)
				(type default)
			)
			(fill no)
			(layer "B.Fab")
		)
		(pad "1" smd rect
			(at 0 -0.9652 270)
			(size 1.397 1.143)
			(layers "B.Cu" "B.Mask" "B.Paste")
			(net "P3V3_M2")
		)
		(pad "2" smd rect
			(at 0 0.9652 270)
			(size 1.397 1.143)
			(layers "B.Cu" "B.Mask" "B.Paste")
			(net "GND")
		)
	)
	(footprint ""
		(layer "B.Cu")
		(at 92.45092 -140.05306 -90)
		(property "Reference" "C137"
			(at 0 0 90)
			(layer "B.SilkS")
			(hide yes)
			(effects
				(font
					(size 1.27 1.27)
				)
				(justify mirror)
			)
		)
		(property "Value" "SCD1U16V2KX-3GP"
			(at -1.1811 -2.7051 270)
			(unlocked yes)
			(layer "B.Fab")
			(hide yes)
			(effects
				(font
					(size 1.016 1.016)
					(thickness 0.1524)
				)
				(justify mirror)
			)
		)
		(property "Device Type" "C402H22"
			(at -1.1811 -4.2291 270)
			(unlocked yes)
			(layer "B.Fab")
			(hide yes)
			(effects
				(font
					(size 1.016 1.016)
					(thickness 0.1524)
				)
				(justify mirror)
			)
		)
		(duplicate_pad_numbers_are_jumpers no)
		(fp_rect
			(start 0.4318 0.9525)
			(end -0.4318 -0.9525)
			(stroke
				(width 0)
				(type default)
			)
			(fill no)
			(layer "B.CrtYd")
		)
		(fp_rect
			(start 0.4318 0.9525)
			(end -0.4318 -0.9525)
			(stroke
				(width 0)
				(type default)
			)
			(fill no)
			(layer "B.Fab")
		)
		(pad "1" smd custom
			(at 0 -0.4445 90)
			(size 0.1524 0.1524)
			(layers "B.Cu" "B.Mask" "B.Paste")
			(net "DEBUG_CARD_PRSNT")
			(options
				(clearance outline)
				(anchor circle)
			)
			(primitives
				(gr_poly
					(pts
						(arc
							(start 0.3048 0.2032)
							(mid 0.275042 0.275042)
							(end 0.2032 0.3048)
						)
						(arc
							(start -0.2032 0.3048)
							(mid -0.275042 0.275042)
							(end -0.3048 0.2032)
						)
						(arc
							(start -0.3048 -0.2032)
							(mid -0.275042 -0.275042)
							(end -0.2032 -0.3048)
						)
						(arc
							(start 0.2032 -0.3048)
							(mid 0.275042 -0.275042)
							(end 0.3048 -0.2032)
						)
					)
					(width 0)
					(fill yes)
				)
			)
		)
		(pad "2" smd custom
			(at 0 0.4445 90)
			(size 0.1524 0.1524)
			(layers "B.Cu" "B.Mask" "B.Paste")
			(net "GND")
			(options
				(clearance outline)
				(anchor circle)
			)
			(primitives
				(gr_poly
					(pts
						(arc
							(start 0.3048 0.2032)
							(mid 0.275042 0.275042)
							(end 0.2032 0.3048)
						)
						(arc
							(start -0.2032 0.3048)
							(mid -0.275042 0.275042)
							(end -0.3048 0.2032)
						)
						(arc
							(start -0.3048 -0.2032)
							(mid -0.275042 -0.275042)
							(end -0.2032 -0.3048)
						)
						(arc
							(start 0.2032 -0.3048)
							(mid 0.275042 -0.275042)
							(end 0.3048 -0.2032)
						)
					)
					(width 0)
					(fill yes)
				)
			)
		)
	)
	(footprint ""
		(layer "B.Cu")
		(at 24.869902 -131.007358 180)
		(property "Reference" "R245"
			(at 0 0 0)
			(layer "B.SilkS")
			(hide yes)
			(effects
				(font
					(size 1.27 1.27)
				)
				(justify mirror)
			)
		)
		(property "Value" "120R2F-GP"
			(at -0.064008 -3.993896 180)
			(unlocked yes)
			(layer "B.Fab")
			(hide yes)
			(effects
				(font
					(size 1.016 1.016)
					(thickness 0.1524)
				)
				(justify mirror)
			)
		)
		(property "Device Type" "R402H16"
			(at -0.064008 -5.517896 180)
			(unlocked yes)
			(layer "B.Fab")
			(hide yes)
			(effects
				(font
					(size 1.016 1.016)
					(thickness 0.1524)
				)
				(justify mirror)
			)
		)
		(duplicate_pad_numbers_are_jumpers no)
		(fp_line
			(start 0.508 -0.9398)
			(end 0.508 0.9398)
			(stroke
				(width 0.1524)
				(type default)
			)
			(layer "B.SilkS")
		)
		(fp_line
			(start -0.508 -0.9398)
			(end 0.508 -0.9398)
			(stroke
				(width 0.1524)
				(type default)
			)
			(layer "B.SilkS")
		)
		(fp_rect
			(start 0.508 0.9398)
			(end -0.508 -0.9398)
			(stroke
				(width 0)
				(type default)
			)
			(fill no)
			(layer "B.CrtYd")
		)
		(fp_rect
			(start 0.508 0.9398)
			(end -0.508 -0.9398)
			(stroke
				(width 0)
				(type default)
			)
			(fill no)
			(layer "B.Fab")
		)
		(pad "1" smd custom
			(at 0 -0.4445)
			(size 0.1397 0.1397)
			(layers "B.Cu" "B.Mask" "B.Paste")
			(net "MEMA_5")
			(options
				(clearance outline)
				(anchor circle)
			)
			(primitives
				(gr_poly
					(pts
						(arc
							(start -0.1778 0.2794)
							(mid -0.249642 0.249642)
							(end -0.2794 0.1778)
						)
						(arc
							(start -0.2794 -0.1778)
							(mid -0.249642 -0.249642)
							(end -0.1778 -0.2794)
						)
						(arc
							(start 0.1778 -0.2794)
							(mid 0.249642 -0.249642)
							(end 0.2794 -0.1778)
						)
						(arc
							(start 0.2794 0.1778)
							(mid 0.249642 0.249642)
							(end 0.1778 0.2794)
						)
					)
					(width 0)
					(fill yes)
				)
			)
		)
		(pad "2" smd custom
			(at 0 0.4445)
			(size 0.1397 0.1397)
			(layers "B.Cu" "B.Mask" "B.Paste")
			(net "P1V2_STBY")
			(options
				(clearance outline)
				(anchor circle)
			)
			(primitives
				(gr_poly
					(pts
						(arc
							(start -0.1778 0.2794)
							(mid -0.249642 0.249642)
							(end -0.2794 0.1778)
						)
						(arc
							(start -0.2794 -0.1778)
							(mid -0.249642 -0.249642)
							(end -0.1778 -0.2794)
						)
						(arc
							(start 0.1778 -0.2794)
							(mid 0.249642 -0.249642)
							(end 0.2794 -0.1778)
						)
						(arc
							(start 0.2794 0.1778)
							(mid 0.249642 0.249642)
							(end 0.1778 0.2794)
						)
					)
					(width 0)
					(fill yes)
				)
			)
		)
	)
	(footprint ""
		(layer "B.Cu")
		(at 37.521642 -155.929584)
		(property "Reference" "R777"
			(at 0 0 0)
			(layer "B.SilkS")
			(hide yes)
			(effects
				(font
					(size 1.27 1.27)
				)
				(justify mirror)
			)
		)
		(property "Value" "1KR2F-3-GP"
			(at -0.064008 -3.993896 0)
			(unlocked yes)
			(layer "B.Fab")
			(hide yes)
			(effects
				(font
					(size 1.016 1.016)
					(thickness 0.1524)
				)
				(justify mirror)
			)
		)
		(property "Device Type" "R402H16"
			(at -0.064008 -5.517896 0)
			(unlocked yes)
			(layer "B.Fab")
			(hide yes)
			(effects
				(font
					(size 1.016 1.016)
					(thickness 0.1524)
				)
				(justify mirror)
			)
		)
		(duplicate_pad_numbers_are_jumpers no)
		(fp_line
			(start -0.508 -0.9398)
			(end 0.508 -0.9398)
			(stroke
				(width 0.1524)
				(type default)
			)
			(layer "B.SilkS")
		)
		(fp_line
			(start 0.508 -0.9398)
			(end 0.508 0.9398)
			(stroke
				(width 0.1524)
				(type default)
			)
			(layer "B.SilkS")
		)
		(fp_rect
			(start 0.508 0.9398)
			(end -0.508 -0.9398)
			(stroke
				(width 0)
				(type default)
			)
			(fill no)
			(layer "B.CrtYd")
		)
		(fp_rect
			(start 0.508 0.9398)
			(end -0.508 -0.9398)
			(stroke
				(width 0)
				(type default)
			)
			(fill no)
			(layer "B.Fab")
		)
		(pad "1" smd custom
			(at 0 -0.4445 180)
			(size 0.1397 0.1397)
			(layers "B.Cu" "B.Mask" "B.Paste")
			(net "ADC_P1V2_STBY")
			(options
				(clearance outline)
				(anchor circle)
			)
			(primitives
				(gr_poly
					(pts
						(arc
							(start -0.1778 0.2794)
							(mid -0.249642 0.249642)
							(end -0.2794 0.1778)
						)
						(arc
							(start -0.2794 -0.1778)
							(mid -0.249642 -0.249642)
							(end -0.1778 -0.2794)
						)
						(arc
							(start 0.1778 -0.2794)
							(mid 0.249642 -0.249642)
							(end 0.2794 -0.1778)
						)
						(arc
							(start 0.2794 0.1778)
							(mid 0.249642 0.249642)
							(end 0.1778 0.2794)
						)
					)
					(width 0)
					(fill yes)
				)
			)
		)
		(pad "2" smd custom
			(at 0 0.4445 180)
			(size 0.1397 0.1397)
			(layers "B.Cu" "B.Mask" "B.Paste")
			(net "GND")
			(options
				(clearance outline)
				(anchor circle)
			)
			(primitives
				(gr_poly
					(pts
						(arc
							(start -0.1778 0.2794)
							(mid -0.249642 0.249642)
							(end -0.2794 0.1778)
						)
						(arc
							(start -0.2794 -0.1778)
							(mid -0.249642 -0.249642)
							(end -0.1778 -0.2794)
						)
						(arc
							(start 0.1778 -0.2794)
							(mid 0.249642 -0.249642)
							(end 0.2794 -0.1778)
						)
						(arc
							(start 0.2794 0.1778)
							(mid 0.249642 0.249642)
							(end 0.1778 0.2794)
						)
					)
					(width 0)
					(fill yes)
				)
			)
		)
	)
	(footprint ""
		(layer "B.Cu")
		(at 174.9552 -127.053086 90)
		(property "Reference" "C624"
			(at 0 0 90)
			(layer "B.SilkS")
			(hide yes)
			(effects
				(font
					(size 1.27 1.27)
				)
				(justify mirror)
			)
		)
		(property "Value" "SCD1U16V2KX-3GP"
			(at -1.1811 -2.7051 90)
			(unlocked yes)
			(layer "B.Fab")
			(hide yes)
			(effects
				(font
					(size 1.016 1.016)
					(thickness 0.1524)
				)
				(justify mirror)
			)
		)
		(property "Device Type" "C402H22"
			(at -1.1811 -4.2291 90)
			(unlocked yes)
			(layer "B.Fab")
			(hide yes)
			(effects
				(font
					(size 1.016 1.016)
					(thickness 0.1524)
				)
				(justify mirror)
			)
		)
		(duplicate_pad_numbers_are_jumpers no)
		(fp_rect
			(start 0.4318 0.9525)
			(end -0.4318 -0.9525)
			(stroke
				(width 0)
				(type default)
			)
			(fill no)
			(layer "B.CrtYd")
		)
		(fp_rect
			(start 0.4318 0.9525)
			(end -0.4318 -0.9525)
			(stroke
				(width 0)
				(type default)
			)
			(fill no)
			(layer "B.Fab")
		)
		(pad "1" smd custom
			(at 0 -0.4445 270)
			(size 0.1524 0.1524)
			(layers "B.Cu" "B.Mask" "B.Paste")
			(net "P3V3_M2")
			(options
				(clearance outline)
				(anchor circle)
			)
			(primitives
				(gr_poly
					(pts
						(arc
							(start 0.3048 0.2032)
							(mid 0.275042 0.275042)
							(end 0.2032 0.3048)
						)
						(arc
							(start -0.2032 0.3048)
							(mid -0.275042 0.275042)
							(end -0.3048 0.2032)
						)
						(arc
							(start -0.3048 -0.2032)
							(mid -0.275042 -0.275042)
							(end -0.2032 -0.3048)
						)
						(arc
							(start 0.2032 -0.3048)
							(mid 0.275042 -0.275042)
							(end 0.3048 -0.2032)
						)
					)
					(width 0)
					(fill yes)
				)
			)
		)
		(pad "2" smd custom
			(at 0 0.4445 270)
			(size 0.1524 0.1524)
			(layers "B.Cu" "B.Mask" "B.Paste")
			(net "GND")
			(options
				(clearance outline)
				(anchor circle)
			)
			(primitives
				(gr_poly
					(pts
						(arc
							(start 0.3048 0.2032)
							(mid 0.275042 0.275042)
							(end 0.2032 0.3048)
						)
						(arc
							(start -0.2032 0.3048)
							(mid -0.275042 0.275042)
							(end -0.3048 0.2032)
						)
						(arc
							(start -0.3048 -0.2032)
							(mid -0.275042 -0.275042)
							(end -0.2032 -0.3048)
						)
						(arc
							(start 0.2032 -0.3048)
							(mid 0.275042 -0.275042)
							(end 0.3048 -0.2032)
						)
					)
					(width 0)
					(fill yes)
				)
			)
		)
	)
	(footprint ""
		(layer "B.Cu")
		(at 91.895168 -158.915608 90)
		(property "Reference" "TP4"
			(at 0 0 90)
			(layer "B.SilkS")
			(hide yes)
			(effects
				(font
					(size 1.27 1.27)
				)
				(justify mirror)
			)
		)
		(property "Value" "TPAD28-2-GP"
			(at 0.0127 -1.6637 90)
			(unlocked yes)
			(layer "B.Fab")
			(hide yes)
			(effects
				(font
					(size 1.016 1.016)
					(thickness 0.1524)
				)
				(justify mirror)
			)
		)
		(property "Device Type" "TPAD28"
			(at 0.0127 -3.1877 90)
			(unlocked yes)
			(layer "B.Fab")
			(hide yes)
			(effects
				(font
					(size 1.016 1.016)
					(thickness 0.1524)
				)
				(justify mirror)
			)
		)
		(duplicate_pad_numbers_are_jumpers no)
		(fp_poly
			(pts
				(arc
					(start 0 0.3556)
					(mid 0 -0.3556)
					(end 0 0.3556)
				)
			)
			(stroke
				(width 0)
				(type default)
			)
			(fill no)
			(layer "B.CrtYd")
		)
		(fp_poly
			(pts
				(arc
					(start 0 0.6096)
					(mid 0 -0.6096)
					(end 0 0.6096)
				)
			)
			(stroke
				(width 0)
				(type default)
			)
			(fill no)
			(layer "B.Fab")
		)
		(pad "1" smd circle
			(at 0 0 270)
			(size 0.7112 0.7112)
			(layers "B.Cu" "B.Mask" "B.Paste")
			(net "PLLFILT")
		)
	)
	(footprint ""
		(layer "B.Cu")
		(at 32.5374 -161.2646 90)
		(property "Reference" "R698"
			(at 0 0 90)
			(layer "B.SilkS")
			(hide yes)
			(effects
				(font
					(size 1.27 1.27)
				)
				(justify mirror)
			)
		)
		(property "Value" "4K7R2F-GP"
			(at -0.064008 -3.993896 90)
			(unlocked yes)
			(layer "B.Fab")
			(hide yes)
			(effects
				(font
					(size 1.016 1.016)
					(thickness 0.1524)
				)
				(justify mirror)
			)
		)
		(property "Device Type" "R402H16"
			(at -0.064008 -5.517896 90)
			(unlocked yes)
			(layer "B.Fab")
			(hide yes)
			(effects
				(font
					(size 1.016 1.016)
					(thickness 0.1524)
				)
				(justify mirror)
			)
		)
		(duplicate_pad_numbers_are_jumpers no)
		(fp_line
			(start 0.508 -0.9398)
			(end 0.508 0.9398)
			(stroke
				(width 0.1524)
				(type default)
			)
			(layer "B.SilkS")
		)
		(fp_line
			(start -0.508 -0.9398)
			(end 0.508 -0.9398)
			(stroke
				(width 0.1524)
				(type default)
			)
			(layer "B.SilkS")
		)
		(fp_rect
			(start 0.508 0.9398)
			(end -0.508 -0.9398)
			(stroke
				(width 0)
				(type default)
			)
			(fill no)
			(layer "B.CrtYd")
		)
		(fp_rect
			(start 0.508 0.9398)
			(end -0.508 -0.9398)
			(stroke
				(width 0)
				(type default)
			)
			(fill no)
			(layer "B.Fab")
		)
		(pad "1" smd custom
			(at 0 -0.4445 270)
			(size 0.1397 0.1397)
			(layers "B.Cu" "B.Mask" "B.Paste")
			(net "P3V3_STBY")
			(options
				(clearance outline)
				(anchor circle)
			)
			(primitives
				(gr_poly
					(pts
						(arc
							(start -0.1778 0.2794)
							(mid -0.249642 0.249642)
							(end -0.2794 0.1778)
						)
						(arc
							(start -0.2794 -0.1778)
							(mid -0.249642 -0.249642)
							(end -0.1778 -0.2794)
						)
						(arc
							(start 0.1778 -0.2794)
							(mid 0.249642 -0.249642)
							(end 0.2794 -0.1778)
						)
						(arc
							(start 0.2794 0.1778)
							(mid 0.249642 0.249642)
							(end 0.1778 0.2794)
						)
					)
					(width 0)
					(fill yes)
				)
			)
		)
		(pad "2" smd custom
			(at 0 0.4445 270)
			(size 0.1397 0.1397)
			(layers "B.Cu" "B.Mask" "B.Paste")
			(net "IOM_TYPE1")
			(options
				(clearance outline)
				(anchor circle)
			)
			(primitives
				(gr_poly
					(pts
						(arc
							(start -0.1778 0.2794)
							(mid -0.249642 0.249642)
							(end -0.2794 0.1778)
						)
						(arc
							(start -0.2794 -0.1778)
							(mid -0.249642 -0.249642)
							(end -0.1778 -0.2794)
						)
						(arc
							(start 0.1778 -0.2794)
							(mid 0.249642 -0.249642)
							(end 0.2794 -0.1778)
						)
						(arc
							(start 0.2794 0.1778)
							(mid 0.249642 0.249642)
							(end 0.1778 0.2794)
						)
					)
					(width 0)
					(fill yes)
				)
			)
		)
	)
	(footprint ""
		(layer "B.Cu")
		(at 24.666702 -143.811244 180)
		(property "Reference" "C69"
			(at 0 0 0)
			(layer "B.SilkS")
			(hide yes)
			(effects
				(font
					(size 1.27 1.27)
				)
				(justify mirror)
			)
		)
		(property "Value" "SCD1U16V2KX-3GP"
			(at -1.1811 -2.7051 180)
			(unlocked yes)
			(layer "B.Fab")
			(hide yes)
			(effects
				(font
					(size 1.016 1.016)
					(thickness 0.1524)
				)
				(justify mirror)
			)
		)
		(property "Device Type" "C402H22"
			(at -1.1811 -4.2291 180)
			(unlocked yes)
			(layer "B.Fab")
			(hide yes)
			(effects
				(font
					(size 1.016 1.016)
					(thickness 0.1524)
				)
				(justify mirror)
			)
		)
		(duplicate_pad_numbers_are_jumpers no)
		(fp_rect
			(start 0.4318 0.9525)
			(end -0.4318 -0.9525)
			(stroke
				(width 0)
				(type default)
			)
			(fill no)
			(layer "B.CrtYd")
		)
		(fp_rect
			(start 0.4318 0.9525)
			(end -0.4318 -0.9525)
			(stroke
				(width 0)
				(type default)
			)
			(fill no)
			(layer "B.Fab")
		)
		(pad "1" smd custom
			(at 0 -0.4445)
			(size 0.1524 0.1524)
			(layers "B.Cu" "B.Mask" "B.Paste")
			(net "GND")
			(options
				(clearance outline)
				(anchor circle)
			)
			(primitives
				(gr_poly
					(pts
						(arc
							(start 0.3048 0.2032)
							(mid 0.275042 0.275042)
							(end 0.2032 0.3048)
						)
						(arc
							(start -0.2032 0.3048)
							(mid -0.275042 0.275042)
							(end -0.3048 0.2032)
						)
						(arc
							(start -0.3048 -0.2032)
							(mid -0.275042 -0.275042)
							(end -0.2032 -0.3048)
						)
						(arc
							(start 0.2032 -0.3048)
							(mid 0.275042 -0.275042)
							(end 0.3048 -0.2032)
						)
					)
					(width 0)
					(fill yes)
				)
			)
		)
		(pad "2" smd custom
			(at 0 0.4445)
			(size 0.1524 0.1524)
			(layers "B.Cu" "B.Mask" "B.Paste")
			(net "P1V2_STBY")
			(options
				(clearance outline)
				(anchor circle)
			)
			(primitives
				(gr_poly
					(pts
						(arc
							(start 0.3048 0.2032)
							(mid 0.275042 0.275042)
							(end 0.2032 0.3048)
						)
						(arc
							(start -0.2032 0.3048)
							(mid -0.275042 0.275042)
							(end -0.3048 0.2032)
						)
						(arc
							(start -0.3048 -0.2032)
							(mid -0.275042 -0.275042)
							(end -0.2032 -0.3048)
						)
						(arc
							(start 0.2032 -0.3048)
							(mid 0.275042 -0.275042)
							(end 0.3048 -0.2032)
						)
					)
					(width 0)
					(fill yes)
				)
			)
		)
	)
)
